(kicad_pcb
	(version 20241229)
	(generator "pcbnew")
	(generator_version "9.0")
	(general
		(thickness 1.711)
		(legacy_teardrops no)
	)
	(paper "A4")
	(title_block
		(title "Antmicro Baseboard for Jetson AGX Thor")
		(date "2026-02-18")
		(rev "1.1.0")
		(company "Antmicro Ltd")
		(comment 1 "www.antmicro.com")
		(comment 9 "footprints 1047-1049 of 1170")
	)
	(layers
		(0 "F.Cu" signal)
		(4 "In1.Cu" signal)
		(6 "In2.Cu" signal)
		(8 "In3.Cu" signal)
		(10 "In4.Cu" jumper)
		(12 "In5.Cu" signal)
		(14 "In6.Cu" signal)
		(16 "In7.Cu" signal)
		(18 "In8.Cu" signal)
		(2 "B.Cu" signal)
		(9 "F.Adhes" user "F.Adhesive")
		(11 "B.Adhes" user "B.Adhesive")
		(13 "F.Paste" user)
		(15 "B.Paste" user)
		(5 "F.SilkS" user "F.Silkscreen")
		(7 "B.SilkS" user "B.Silkscreen")
		(1 "F.Mask" user)
		(3 "B.Mask" user)
		(17 "Dwgs.User" user "User.Drawings")
		(19 "Cmts.User" user "User.Comments")
		(21 "Eco1.User" user "User.Eco1")
		(23 "Eco2.User" user "User.Eco2")
		(25 "Edge.Cuts" user)
		(27 "Margin" user)
		(31 "F.CrtYd" user "F.Courtyard")
		(29 "B.CrtYd" user "B.Courtyard")
		(35 "F.Fab" user)
		(33 "B.Fab" user)
	)
	(footprint "antmicro-footprints:Spacer_Drill3.7mm_H2.5mm_9774025151R"
		(locked yes)
		(layer "B.Cu")
		(at 197.66 104.501 90)
		(descr "Spacer M=3 h=2.5mm fi=5.1mm")
		(property "Reference" "H9"
			(at 0 3.2 90)
			(layer "B.SilkS")
			(effects
				(font
					(size 0.7 0.7)
					(thickness 0.15)
				)
				(justify right top mirror)
			)
		)
		(property "Value" "Spacer_Drill3.7mm_H2.5mm_9774025151R"
			(at 0 -4 90)
			(layer "B.Fab")
			(effects
				(font
					(size 0.7 0.7)
					(thickness 0.15)
				)
				(justify right top mirror)
			)
		)
		(property "Datasheet" "https://www.we-online.com/components/products/datasheet/9774025151R.pdf"
			(at 0 0 90)
			(layer "B.Fab")
			(hide yes)
			(effects
				(font
					(size 1.27 1.27)
					(thickness 0.15)
				)
				(justify mirror)
			)
		)
		(property "Description" "Spacer, SMT, Non Stop, Steel, Swage Round, 5.1 mm x 2.5 mm, M2.5 Thread, WA-SMSI Series"
			(at 0 0 90)
			(layer "B.Fab")
			(hide yes)
			(effects
				(font
					(size 1.27 1.27)
					(thickness 0.15)
				)
				(justify mirror)
			)
		)
		(property "Manufacturer" "Würth Elektronik"
			(at 0 0 270)
			(unlocked yes)
			(layer "B.Fab")
			(hide yes)
			(effects
				(font
					(size 1 1)
					(thickness 0.15)
				)
				(justify mirror)
			)
		)
		(property "MPN" "9774025151R"
			(at 0 0 270)
			(unlocked yes)
			(layer "B.Fab")
			(hide yes)
			(effects
				(font
					(size 1 1)
					(thickness 0.15)
				)
				(justify mirror)
			)
		)
		(property "Author" "Antmicro"
			(at 0 0 270)
			(unlocked yes)
			(layer "B.Fab")
			(hide yes)
			(effects
				(font
					(size 1 1)
					(thickness 0.15)
				)
				(justify mirror)
			)
		)
		(property "License" "Apache-2.0"
			(at 0 0 270)
			(unlocked yes)
			(layer "B.Fab")
			(hide yes)
			(effects
				(font
					(size 1 1)
					(thickness 0.15)
				)
				(justify mirror)
			)
		)
		(sheetname "/M.2/")
		(sheetfile "m2.kicad_sch")
		(solder_paste_margin_ratio -1)
		(attr smd)
		(fp_circle
			(center 0 0)
			(end 3.05 0)
			(stroke
				(width 0.05)
				(type solid)
			)
			(fill no)
			(layer "B.CrtYd")
		)
		(fp_circle
			(center 0 0)
			(end 2.6 0)
			(stroke
				(width 0.15)
				(type solid)
			)
			(fill no)
			(layer "B.Fab")
		)
		(fp_text user "License: Apache-2.0"
			(at -9.6 -8.9 90)
			(layer "B.Fab")
			(effects
				(font
					(size 0.7 0.7)
					(thickness 0.15)
				)
				(justify right top mirror)
			)
		)
		(fp_text user "Author: Antmicro"
			(at -9.6 -7.7 90)
			(layer "B.Fab")
			(effects
				(font
					(size 0.7 0.7)
					(thickness 0.15)
				)
				(justify right top mirror)
			)
		)
		(fp_text user "${REFERENCE}"
			(at -9.6 -6.5 90)
			(layer "B.Fab")
			(effects
				(font
					(size 0.7 0.7)
					(thickness 0.15)
				)
				(justify right top mirror)
			)
		)
		(pad "" smd custom
			(at -1.7 -1.7)
			(size 0.62 0.62)
			(layers "B.Paste")
			(thermal_bridge_angle 90)
			(options
				(clearance outline)
				(anchor circle)
			)
			(primitives
				(gr_arc
					(start 1.266786 0.24747)
					(mid 0.285453 -0.29439)
					(end -0.250195 -1.279127)
					(width 0.2)
				)
				(gr_arc
					(start 1.259603 0.339191)
					(mid 0.218448 -0.232561)
					(end -0.34334 -1.279127)
					(width 0.2)
				)
				(gr_arc
					(start 1.255279 0.431435)
					(mid 0.152481 -0.169693)
					(end -0.436309 -1.279127)
					(width 0.2)
				)
				(gr_arc
					(start 1.253811 0.524161)
					(mid 0.087542 -0.105784)
					(end -0.529126 -1.279127)
					(width 0.2)
				)
				(gr_arc
					(start 1.275473 0.621136)
					(mid 0.0309 -0.033527)
					(end -0.621807 -1.279127)
					(width 0.2)
				)
				(gr_arc
					(start 1.263664 0.711602)
					(mid -0.037759 0.026651)
					(end -0.71437 -1.279127)
					(width 0.2)
				)
				(gr_arc
					(start 1.253435 0.802342)
					(mid -0.105837 0.087395)
					(end -0.806826 -1.279127)
					(width 0.2)
				)
				(gr_arc
					(start 1.267475 0.897258)
					(mid -0.165236 0.156885)
					(end -0.899187 -1.279127)
					(width 0.2)
				)
				(gr_arc
					(start 1.270645 0.990112)
					(mid -0.228522 0.222449)
					(end -0.991463 -1.279127)
					(width 0.2)
				)
				(gr_arc
					(start 1.266278 1.081674)
					(mid -0.294507 0.285313)
					(end -1.083663 -1.279127)
					(width 0.2)
				)
				(gr_line
					(start 1.279127 0.250195)
					(end 1.279127 1.083663)
					(width 0.2)
				)
				(gr_line
					(start -0.250195 -1.279127)
					(end -1.083663 -1.279127)
					(width 0.2)
				)
			)
		)
		(pad "" smd custom
			(at -1.7 1.7 90)
			(size 0.62 0.62)
			(layers "B.Paste")
			(thermal_bridge_angle 90)
			(options
				(clearance outline)
				(anchor circle)
			)
			(primitives
				(gr_arc
					(start 1.266786 0.24747)
					(mid 0.285453 -0.29439)
					(end -0.250195 -1.279127)
					(width 0.2)
				)
				(gr_arc
					(start 1.259603 0.339191)
					(mid 0.218448 -0.232561)
					(end -0.34334 -1.279127)
					(width 0.2)
				)
				(gr_arc
					(start 1.255279 0.431435)
					(mid 0.152481 -0.169693)
					(end -0.436309 -1.279127)
					(width 0.2)
				)
				(gr_arc
					(start 1.253811 0.524161)
					(mid 0.087542 -0.105784)
					(end -0.529126 -1.279127)
					(width 0.2)
				)
				(gr_arc
					(start 1.275473 0.621136)
					(mid 0.0309 -0.033527)
					(end -0.621807 -1.279127)
					(width 0.2)
				)
				(gr_arc
					(start 1.263664 0.711602)
					(mid -0.037759 0.026651)
					(end -0.71437 -1.279127)
					(width 0.2)
				)
				(gr_arc
					(start 1.253435 0.802342)
					(mid -0.105837 0.087395)
					(end -0.806826 -1.279127)
					(width 0.2)
				)
				(gr_arc
					(start 1.267475 0.897258)
					(mid -0.165236 0.156885)
					(end -0.899187 -1.279127)
					(width 0.2)
				)
				(gr_arc
					(start 1.270645 0.990112)
					(mid -0.228522 0.222449)
					(end -0.991463 -1.279127)
					(width 0.2)
				)
				(gr_arc
					(start 1.266278 1.081674)
					(mid -0.294507 0.285313)
					(end -1.083663 -1.279127)
					(width 0.2)
				)
				(gr_line
					(start 1.279127 0.250195)
					(end 1.279127 1.083663)
					(width 0.2)
				)
				(gr_line
					(start -0.250195 -1.279127)
					(end -1.083663 -1.279127)
					(width 0.2)
				)
			)
		)
		(pad "" smd custom
			(at 1.7 -1.7 270)
			(size 0.62 0.62)
			(layers "B.Paste")
			(thermal_bridge_angle 90)
			(options
				(clearance outline)
				(anchor circle)
			)
			(primitives
				(gr_arc
					(start 1.266786 0.24747)
					(mid 0.285453 -0.29439)
					(end -0.250195 -1.279127)
					(width 0.2)
				)
				(gr_arc
					(start 1.259603 0.339191)
					(mid 0.218448 -0.232561)
					(end -0.34334 -1.279127)
					(width 0.2)
				)
				(gr_arc
					(start 1.255279 0.431435)
					(mid 0.152481 -0.169693)
					(end -0.436309 -1.279127)
					(width 0.2)
				)
				(gr_arc
					(start 1.253811 0.524161)
					(mid 0.087542 -0.105784)
					(end -0.529126 -1.279127)
					(width 0.2)
				)
				(gr_arc
					(start 1.275473 0.621136)
					(mid 0.0309 -0.033527)
					(end -0.621807 -1.279127)
					(width 0.2)
				)
				(gr_arc
					(start 1.263664 0.711602)
					(mid -0.037759 0.026651)
					(end -0.71437 -1.279127)
					(width 0.2)
				)
				(gr_arc
					(start 1.253435 0.802342)
					(mid -0.105837 0.087395)
					(end -0.806826 -1.279127)
					(width 0.2)
				)
				(gr_arc
					(start 1.267475 0.897258)
					(mid -0.165236 0.156885)
					(end -0.899187 -1.279127)
					(width 0.2)
				)
				(gr_arc
					(start 1.270645 0.990112)
					(mid -0.228522 0.222449)
					(end -0.991463 -1.279127)
					(width 0.2)
				)
				(gr_arc
					(start 1.266278 1.081674)
					(mid -0.294507 0.285313)
					(end -1.083663 -1.279127)
					(width 0.2)
				)
				(gr_line
					(start 1.279127 0.250195)
					(end 1.279127 1.083663)
					(width 0.2)
				)
				(gr_line
					(start -0.250195 -1.279127)
					(end -1.083663 -1.279127)
					(width 0.2)
				)
			)
		)
		(pad "" smd custom
			(at 1.7 1.7 180)
			(size 0.62 0.62)
			(layers "B.Paste")
			(thermal_bridge_angle 90)
			(options
				(clearance outline)
				(anchor circle)
			)
			(primitives
				(gr_arc
					(start 1.266786 0.24747)
					(mid 0.285453 -0.29439)
					(end -0.250195 -1.279127)
					(width 0.2)
				)
				(gr_arc
					(start 1.259603 0.339191)
					(mid 0.218448 -0.232561)
					(end -0.34334 -1.279127)
					(width 0.2)
				)
				(gr_arc
					(start 1.255279 0.431435)
					(mid 0.152481 -0.169693)
					(end -0.436309 -1.279127)
					(width 0.2)
				)
				(gr_arc
					(start 1.253811 0.524161)
					(mid 0.087542 -0.105784)
					(end -0.529126 -1.279127)
					(width 0.2)
				)
				(gr_arc
					(start 1.275473 0.621136)
					(mid 0.0309 -0.033527)
					(end -0.621807 -1.279127)
					(width 0.2)
				)
				(gr_arc
					(start 1.263664 0.711602)
					(mid -0.037759 0.026651)
					(end -0.71437 -1.279127)
					(width 0.2)
				)
				(gr_arc
					(start 1.253435 0.802342)
					(mid -0.105837 0.087395)
					(end -0.806826 -1.279127)
					(width 0.2)
				)
				(gr_arc
					(start 1.267475 0.897258)
					(mid -0.165236 0.156885)
					(end -0.899187 -1.279127)
					(width 0.2)
				)
				(gr_arc
					(start 1.270645 0.990112)
					(mid -0.228522 0.222449)
					(end -0.991463 -1.279127)
					(width 0.2)
				)
				(gr_arc
					(start 1.266278 1.081674)
					(mid -0.294507 0.285313)
					(end -1.083663 -1.279127)
					(width 0.2)
				)
				(gr_line
					(start 1.279127 0.250195)
					(end 1.279127 1.083663)
					(width 0.2)
				)
				(gr_line
					(start -0.250195 -1.279127)
					(end -1.083663 -1.279127)
					(width 0.2)
				)
			)
		)
		(pad "1" thru_hole circle
			(at 0 0 90)
			(size 6 6)
			(drill 3.7)
			(layers "*.Cu" "*.Mask")
			(remove_unused_layers no)
			(net 1 "GND")
			(pintype "passive")
		)
	)
	(footprint "antmicro-footprints:C_0402_1005Metric"
		(layer "B.Cu")
		(at 94 118.77 180)
		(descr "Capacitor SMD 0402")
		(tags "capacitor SMD 0402")
		(property "Reference" "C211"
			(at -3.8 -0.655 0)
			(layer "B.SilkS")
			(effects
				(font
					(size 0.7 0.7)
					(thickness 0.15)
				)
				(justify left bottom mirror)
			)
		)
		(property "Value" "C_220n_0402"
			(at -1.022927 -2.155213 0)
			(layer "B.Fab")
			(effects
				(font
					(size 0.7 0.7)
					(thickness 0.15)
				)
				(justify left bottom mirror)
			)
		)
		(property "Datasheet" "https://www.yageo.com/en/Chart/Download/pdf/CC0402KRX5R6BB224"
			(at 0 0 0)
			(layer "B.Fab")
			(hide yes)
			(effects
				(font
					(size 1.27 1.27)
					(thickness 0.15)
				)
				(justify mirror)
			)
		)
		(property "Description" "SMD Multilayer Ceramic Capacitor, 0.22 µF, 10 V, 0402 [1005 Metric], ± 10%, X5R, CC Series"
			(at 0 0 0)
			(layer "B.Fab")
			(hide yes)
			(effects
				(font
					(size 1.27 1.27)
					(thickness 0.15)
				)
				(justify mirror)
			)
		)
		(property "MPN" "CC0402KRX5R6BB224"
			(at 0 0 180)
			(unlocked yes)
			(layer "B.Fab")
			(hide yes)
			(effects
				(font
					(size 1 1)
					(thickness 0.15)
				)
				(justify mirror)
			)
		)
		(property "Val" "220n"
			(at 0 0 180)
			(unlocked yes)
			(layer "B.Fab")
			(hide yes)
			(effects
				(font
					(size 1 1)
					(thickness 0.15)
				)
				(justify mirror)
			)
		)
		(property "Voltage" "25V"
			(at 0 0 180)
			(unlocked yes)
			(layer "B.Fab")
			(hide yes)
			(effects
				(font
					(size 1 1)
					(thickness 0.15)
				)
				(justify mirror)
			)
		)
		(property "Dielectric" "X7R"
			(at 0 0 180)
			(unlocked yes)
			(layer "B.Fab")
			(hide yes)
			(effects
				(font
					(size 1 1)
					(thickness 0.15)
				)
				(justify mirror)
			)
		)
		(property "Manufacturer" "YAGEO"
			(at 0 0 180)
			(unlocked yes)
			(layer "B.Fab")
			(hide yes)
			(effects
				(font
					(size 1 1)
					(thickness 0.15)
				)
				(justify mirror)
			)
		)
		(property "License" "Apache-2.0"
			(at 0 0 180)
			(unlocked yes)
			(layer "B.Fab")
			(hide yes)
			(effects
				(font
					(size 1 1)
					(thickness 0.15)
				)
				(justify mirror)
			)
		)
		(property "Author" "Antmicro"
			(at 0 0 180)
			(unlocked yes)
			(layer "B.Fab")
			(hide yes)
			(effects
				(font
					(size 1 1)
					(thickness 0.15)
				)
				(justify mirror)
			)
		)
		(property "Public" "False"
			(at 0 0 180)
			(unlocked yes)
			(layer "B.Fab")
			(hide yes)
			(effects
				(font
					(size 1 1)
					(thickness 0.15)
				)
				(justify mirror)
			)
		)
		(sheetname "/Expansion connector/")
		(sheetfile "expansion_connector.kicad_sch")
		(attr smd)
		(fp_poly
			(pts
				(xy -0.925 0.47) (xy 0.925 0.47) (xy 0.925 -0.47) (xy -0.925 -0.47)
			)
			(stroke
				(width 0.05)
				(type default)
			)
			(fill no)
			(layer "B.CrtYd")
		)
		(fp_line
			(start 0.504 0.25)
			(end 0.504 -0.248)
			(stroke
				(width 0.15)
				(type solid)
			)
			(layer "B.Fab")
		)
		(fp_line
			(start 0.504 -0.248)
			(end -0.494 -0.248)
			(stroke
				(width 0.15)
				(type solid)
			)
			(layer "B.Fab")
		)
		(fp_line
			(start -0.494 0.25)
			(end 0.504 0.25)
			(stroke
				(width 0.15)
				(type solid)
			)
			(layer "B.Fab")
		)
		(fp_line
			(start -0.494 -0.248)
			(end -0.494 0.25)
			(stroke
				(width 0.15)
				(type solid)
			)
			(layer "B.Fab")
		)
		(fp_text user "Author: Antmicro"
			(at -0.939 -3.399 0)
			(layer "B.Fab")
			(effects
				(font
					(size 0.7 0.7)
					(thickness 0.15)
				)
				(justify left bottom mirror)
			)
		)
		(fp_text user "License: Apache-2.0"
			(at -0.939 -5.799 0)
			(layer "B.Fab")
			(effects
				(font
					(size 0.7 0.7)
					(thickness 0.15)
				)
				(justify left bottom mirror)
			)
		)
		(fp_text user "${REFERENCE}"
			(at -0.939 -4.599 0)
			(layer "B.Fab")
			(effects
				(font
					(size 0.7 0.7)
					(thickness 0.15)
				)
				(justify left bottom mirror)
			)
		)
		(pad "1" smd roundrect
			(at -0.48 0 180)
			(size 0.59 0.64)
			(layers "B.Cu" "B.Mask" "B.Paste")
			(roundrect_rratio 0.25)
			(net 459 "/Expansion connector/PCIe_{C3x2}.TX0+")
			(pintype "passive")
		)
		(pad "2" smd roundrect
			(at 0.48 0 180)
			(size 0.59 0.64)
			(layers "B.Cu" "B.Mask" "B.Paste")
			(roundrect_rratio 0.25)
			(net 452 "/Expansion connector/PET0_C3_P")
			(pintype "passive")
		)
	)
	(footprint "antmicro-footprints:R_0402_1005Metric"
		(layer "B.Cu")
		(at 203.4 106.800001)
		(descr "Resistor SMD 0402")
		(tags "resistor SMD 0402")
		(property "Reference" "R283"
			(at 1.1 -0.300001 0)
			(layer "B.SilkS")
			(effects
				(font
					(size 0.7 0.7)
					(thickness 0.15)
				)
				(justify right top mirror)
			)
		)
		(property "Value" "R_0R_0402"
			(at -1.011843 -1.772046 0)
			(layer "B.Fab")
			(effects
				(font
					(size 0.7 0.7)
					(thickness 0.15)
				)
				(justify right top mirror)
			)
		)
		(property "Datasheet" "https://industrial.panasonic.com/cdbs/www-data/pdf/RDA0000/AOA0000C301.pdf"
			(at 0 0 0)
			(layer "B.Fab")
			(hide yes)
			(effects
				(font
					(size 1.27 1.27)
					(thickness 0.15)
				)
				(justify mirror)
			)
		)
		(property "Description" "SMD Chip Resistor, Jumper, 0 ohm, 100 mW, 0402 [1005 Metric], Thick Film, General Purpose"
			(at 0 0 0)
			(layer "B.Fab")
			(hide yes)
			(effects
				(font
					(size 1.27 1.27)
					(thickness 0.15)
				)
				(justify mirror)
			)
		)
		(property "Manufacturer" "Panasonic"
			(at 0 0 180)
			(unlocked yes)
			(layer "B.Fab")
			(hide yes)
			(effects
				(font
					(size 1 1)
					(thickness 0.15)
				)
				(justify mirror)
			)
		)
		(property "MPN" "ERJ2GE0R00X"
			(at 0 0 180)
			(unlocked yes)
			(layer "B.Fab")
			(hide yes)
			(effects
				(font
					(size 1 1)
					(thickness 0.15)
				)
				(justify mirror)
			)
		)
		(property "Val" "0R"
			(at 0 0 180)
			(unlocked yes)
			(layer "B.Fab")
			(hide yes)
			(effects
				(font
					(size 1 1)
					(thickness 0.15)
				)
				(justify mirror)
			)
		)
		(property "License" "Apache-2.0"
			(at 0 0 180)
			(unlocked yes)
			(layer "B.Fab")
			(hide yes)
			(effects
				(font
					(size 1 1)
					(thickness 0.15)
				)
				(justify mirror)
			)
		)
		(property "Author" "Antmicro"
			(at 0 0 180)
			(unlocked yes)
			(layer "B.Fab")
			(hide yes)
			(effects
				(font
					(size 1 1)
					(thickness 0.15)
				)
				(justify mirror)
			)
		)
		(property "Tolerance" "~"
			(at 0 0 180)
			(unlocked yes)
			(layer "B.Fab")
			(hide yes)
			(effects
				(font
					(size 1 1)
					(thickness 0.15)
				)
				(justify mirror)
			)
		)
		(property "Current" "1A"
			(at 0 0 180)
			(unlocked yes)
			(layer "B.Fab")
			(hide yes)
			(effects
				(font
					(size 1 1)
					(thickness 0.15)
				)
				(justify mirror)
			)
		)
		(sheetname "/Recovery USB/")
		(sheetfile "recovery_usb.kicad_sch")
		(attr smd exclude_from_pos_files exclude_from_bom dnp)
		(fp_poly
			(pts
				(xy -0.925 0.47) (xy -0.925 -0.47) (xy 0.925 -0.47) (xy 0.925 0.47)
			)
			(stroke
				(width 0.05)
				(type default)
			)
			(fill no)
			(layer "B.CrtYd")
		)
		(fp_poly
			(pts
				(xy -0.5 0.25) (xy -0.5 -0.25) (xy 0.5 -0.25) (xy 0.5 0.25)
			)
			(stroke
				(width 0.15)
				(type solid)
			)
			(fill no)
			(layer "B.Fab")
		)
		(fp_text user "Author: Antmicro"
			(at -0.95 -4.169 0)
			(layer "B.Fab")
			(effects
				(font
					(size 0.7 0.7)
					(thickness 0.15)
				)
				(justify right top mirror)
			)
		)
		(fp_text user "${REFERENCE}"
			(at -0.95 -3.168 0)
			(layer "B.Fab")
			(effects
				(font
					(size 0.7 0.7)
					(thickness 0.15)
				)
				(justify right top mirror)
			)
		)
		(fp_text user "License: Apache-2.0"
			(at -0.949999 -5.169 0)
			(layer "B.Fab")
			(effects
				(font
					(size 0.7 0.7)
					(thickness 0.15)
				)
				(justify right top mirror)
			)
		)
		(pad "1" smd roundrect
			(at -0.48 0)
			(size 0.59 0.64)
			(layers "B.Cu" "B.Mask" "B.Paste")
			(roundrect_rratio 0.25)
			(net 1026 "/Recovery USB/~{USBC2_INT}")
			(pintype "passive")
		)
		(pad "2" smd roundrect
			(at 0.48 0)
			(size 0.59 0.64)
			(layers "B.Cu" "B.Mask" "B.Paste")
			(roundrect_rratio 0.25)
			(net 1366 "/Recovery USB/~{USBC2_INT_R}")
			(pintype "passive")
		)
	)
)
